# SCM (Grand Teton) — schematic netlist excerpt (pin names and nets, part order shuffled) for the footprints in the layout excerpt that follows; sources: Cadence DE-HDL packaged netlist, KiCad conversion of 12092022_DA0F0TMDCD0_F0T_Management_Board_D_brd_V3_OCP.brd

R189  Q_RES  1K 1% CHIP  pkg 0402LF  page 14 : A = P1V2_P1V0_I3C_VDDL1 ; B = I3C3_SPD_SDA
R363  Q_RES  120 1% CHIP  pkg 0402LF  page 20 : A = M_BMC_DDR4_MA<12> ; B = P1V2_AUX

(kicad_pcb
	(version 20260206)
	(generator "pcbnew")
	(generator_version "10.0")
	(general
		(thickness 1.6)
		(legacy_teardrops no)
	)
	(paper "A4")
	(title_block
		(title "12092022_DA0F0TMDCD0_F0T_Management_Board_D_brd_V3_OCP.brd")
		(comment 1 "Grand Teton / footprints 957-958 of 1440")
	)
	(layers
		(0 "F.Cu" signal "TOP")
		(4 "In1.Cu" signal "GND")
		(6 "In2.Cu" signal "IN1")
		(8 "In3.Cu" signal "GND1")
		(10 "In4.Cu" signal "IN2")
		(12 "In5.Cu" signal "VCC")
		(14 "In6.Cu" signal "VCC1")
		(16 "In7.Cu" signal "IN3")
		(18 "In8.Cu" signal "GND2")
		(20 "In9.Cu" signal "IN4")
		(22 "In10.Cu" signal "GND3")
		(2 "B.Cu" signal "BOTTOM")
		(9 "F.Adhes" user "F.Adhesive")
		(11 "B.Adhes" user "B.Adhesive")
		(13 "F.Paste" user "Package Geometry/Pastemask Top")
		(15 "B.Paste" user "Package Geometry/Pastemask Bottom")
		(5 "F.SilkS" user "Ref Des/Silkscreen Top")
		(7 "B.SilkS" user "Ref Des/Silkscreen Bottom")
		(1 "F.Mask" user "Board Geometry/Soldermask Top")
		(3 "B.Mask" user "Board Geometry/Soldermask Bottom")
		(17 "Dwgs.User" user "User.Drawings")
		(19 "Cmts.User" user "User.Comments")
		(21 "Eco1.User" user "User.Eco1")
		(23 "Eco2.User" user "User.Eco2")
		(25 "Edge.Cuts" user "Board Geometry/Outline")
		(27 "Margin" user)
		(31 "F.CrtYd" user "Package Geometry/Place Bound Top")
		(29 "B.CrtYd" user "Package Geometry/Place Bound Bottom")
		(35 "F.Fab" user "Ref Des/Assembly Top")
		(33 "B.Fab" user "Ref Des/Assembly Bottom")
	)
	(footprint ""
		(layer "B.Cu")
		(at 39.80053 -65.77965 -90)
		(property "Reference" "R189"
			(at 0 0 90)
			(layer "B.SilkS")
			(hide yes)
			(effects
				(font
					(size 1.27 1.27)
				)
				(justify mirror)
			)
		)
		(property "Value" ""
			(at 0 0 90)
			(layer "B.Fab")
			(effects
				(font
					(size 1.27 1.27)
				)
				(justify mirror)
			)
		)
		(duplicate_pad_numbers_are_jumpers no)
		(fp_line
			(start -0.7874 0.4064)
			(end 0.7874 0.4064)
			(stroke
				(width 0.1524)
				(type default)
			)
			(layer "B.SilkS")
		)
		(fp_line
			(start 0.7874 0.4064)
			(end 0.7874 -0.4064)
			(stroke
				(width 0.1524)
				(type default)
			)
			(layer "B.SilkS")
		)
		(fp_line
			(start -0.7874 -0.4064)
			(end -0.7874 0.4064)
			(stroke
				(width 0.1524)
				(type default)
			)
			(layer "B.SilkS")
		)
		(fp_line
			(start 0.7874 -0.4064)
			(end -0.7874 -0.4064)
			(stroke
				(width 0.1524)
				(type default)
			)
			(layer "B.SilkS")
		)
		(fp_line
			(start -0.67945 0.3048)
			(end -0.120396 0.3048)
			(stroke
				(width 0.1)
				(type default)
			)
			(layer "B.Fab")
		)
		(fp_line
			(start -0.120396 0.3048)
			(end -0.120396 0.2794)
			(stroke
				(width 0.1)
				(type default)
			)
			(layer "B.Fab")
		)
		(fp_line
			(start 0.12065 0.3048)
			(end 0.67945 0.3048)
			(stroke
				(width 0.1)
				(type default)
			)
			(layer "B.Fab")
		)
		(fp_line
			(start 0.67945 0.3048)
			(end 0.67945 -0.305054)
			(stroke
				(width 0.1)
				(type default)
			)
			(layer "B.Fab")
		)
		(fp_line
			(start -0.120396 0.2794)
			(end 0.12065 0.2794)
			(stroke
				(width 0.1)
				(type default)
			)
			(layer "B.Fab")
		)
		(fp_line
			(start 0.12065 0.2794)
			(end 0.12065 0.3048)
			(stroke
				(width 0.1)
				(type default)
			)
			(layer "B.Fab")
		)
		(fp_line
			(start -0.12065 -0.2794)
			(end -0.12065 -0.3048)
			(stroke
				(width 0.1)
				(type default)
			)
			(layer "B.Fab")
		)
		(fp_line
			(start 0.12065 -0.2794)
			(end -0.12065 -0.2794)
			(stroke
				(width 0.1)
				(type default)
			)
			(layer "B.Fab")
		)
		(fp_line
			(start -0.67945 -0.3048)
			(end -0.67945 0.3048)
			(stroke
				(width 0.1)
				(type default)
			)
			(layer "B.Fab")
		)
		(fp_line
			(start -0.12065 -0.3048)
			(end -0.67945 -0.3048)
			(stroke
				(width 0.1)
				(type default)
			)
			(layer "B.Fab")
		)
		(fp_line
			(start 0.12065 -0.305054)
			(end 0.12065 -0.2794)
			(stroke
				(width 0.1)
				(type default)
			)
			(layer "B.Fab")
		)
		(fp_line
			(start 0.67945 -0.305054)
			(end 0.12065 -0.305054)
			(stroke
				(width 0.1)
				(type default)
			)
			(layer "B.Fab")
		)
		(pad "1" smd circle
			(at 0.40005 0 90)
			(size 0 0)
			(layers "B.Cu" "B.Mask" "B.Paste")
			(net "P1V2_P1V0_I3C_VDDL1")
		)
		(pad "2" smd circle
			(at -0.40005 0 90)
			(size 0 0)
			(layers "B.Cu" "B.Mask" "B.Paste")
			(net "I3C3_SPD_SDA")
		)
	)
	(footprint ""
		(layer "B.Cu")
		(at 83.16722 -44.554394 180)
		(property "Reference" "R363"
			(at 0 0 0)
			(layer "B.SilkS")
			(hide yes)
			(effects
				(font
					(size 1.27 1.27)
				)
				(justify mirror)
			)
		)
		(property "Value" ""
			(at 0 0 0)
			(layer "B.Fab")
			(effects
				(font
					(size 1.27 1.27)
				)
				(justify mirror)
			)
		)
		(duplicate_pad_numbers_are_jumpers no)
		(fp_line
			(start 0.7874 0.4064)
			(end 0.7874 -0.4064)
			(stroke
				(width 0.1524)
				(type default)
			)
			(layer "B.SilkS")
		)
		(fp_line
			(start 0.7874 -0.4064)
			(end -0.7874 -0.4064)
			(stroke
				(width 0.1524)
				(type default)
			)
			(layer "B.SilkS")
		)
		(fp_line
			(start -0.7874 0.4064)
			(end 0.7874 0.4064)
			(stroke
				(width 0.1524)
				(type default)
			)
			(layer "B.SilkS")
		)
		(fp_line
			(start -0.7874 -0.4064)
			(end -0.7874 0.4064)
			(stroke
				(width 0.1524)
				(type default)
			)
			(layer "B.SilkS")
		)
		(fp_line
			(start 0.67945 0.3048)
			(end 0.67945 -0.305054)
			(stroke
				(width 0.1)
				(type default)
			)
			(layer "B.Fab")
		)
		(fp_line
			(start 0.67945 -0.305054)
			(end 0.12065 -0.305054)
			(stroke
				(width 0.1)
				(type default)
			)
			(layer "B.Fab")
		)
		(fp_line
			(start 0.12065 0.3048)
			(end 0.67945 0.3048)
			(stroke
				(width 0.1)
				(type default)
			)
			(layer "B.Fab")
		)
		(fp_line
			(start 0.12065 0.2794)
			(end 0.12065 0.3048)
			(stroke
				(width 0.1)
				(type default)
			)
			(layer "B.Fab")
		)
		(fp_line
			(start 0.12065 -0.2794)
			(end -0.12065 -0.2794)
			(stroke
				(width 0.1)
				(type default)
			)
			(layer "B.Fab")
		)
		(fp_line
			(start 0.12065 -0.305054)
			(end 0.12065 -0.2794)
			(stroke
				(width 0.1)
				(type default)
			)
			(layer "B.Fab")
		)
		(fp_line
			(start -0.120396 0.3048)
			(end -0.120396 0.2794)
			(stroke
				(width 0.1)
				(type default)
			)
			(layer "B.Fab")
		)
		(fp_line
			(start -0.120396 0.2794)
			(end 0.12065 0.2794)
			(stroke
				(width 0.1)
				(type default)
			)
			(layer "B.Fab")
		)
		(fp_line
			(start -0.12065 -0.2794)
			(end -0.12065 -0.3048)
			(stroke
				(width 0.1)
				(type default)
			)
			(layer "B.Fab")
		)
		(fp_line
			(start -0.12065 -0.3048)
			(end -0.67945 -0.3048)
			(stroke
				(width 0.1)
				(type default)
			)
			(layer "B.Fab")
		)
		(fp_line
			(start -0.67945 0.3048)
			(end -0.120396 0.3048)
			(stroke
				(width 0.1)
				(type default)
			)
			(layer "B.Fab")
		)
		(fp_line
			(start -0.67945 -0.3048)
			(end -0.67945 0.3048)
			(stroke
				(width 0.1)
				(type default)
			)
			(layer "B.Fab")
		)
		(pad "1" smd circle
			(at 0.40005 0)
			(size 0 0)
			(layers "B.Cu" "B.Mask" "B.Paste")
			(net "M_BMC_DDR4_MA<12>")
		)
		(pad "2" smd circle
			(at -0.40005 0)
			(size 0 0)
			(layers "B.Cu" "B.Mask" "B.Paste")
			(net "P1V2_AUX")
		)
	)
)
